# S9S_MB_2U (Grand Teton) — schematic netlist excerpt (pin names and nets, part order shuffled) for the footprints in the layout excerpt that follows; sources: Cadence DE-HDL packaged netlist, KiCad conversion of 03242023_DA0F0TMBIJ0_F0T_Motherboard_J_brd_V01_OCP.brd

PR140  Q_RES  2.2 1% CHIP  pkg 0402LF  page 269 : A = PVCCIN_CPU0_PVCC ; B = PVCCIN_CPU0_VDD6
R2510  Q_RES  10K 1% EMPTY  pkg 0402LF  page 184 : A = P3V3_AUX ; B = FM_M2_E1S_E6_PEDET
C393  Q_CAP  47UF 4V 20% X6S  pkg C0805  page 75 : A = PVCCIN_CPU0 ; B = GND

(kicad_pcb
	(version 20260206)
	(generator "pcbnew")
	(generator_version "10.0")
	(general
		(thickness 1.6)
		(legacy_teardrops no)
	)
	(paper "A4")
	(title_block
		(title "03242023_DA0F0TMBIJ0_F0T_Motherboard_J_brd_V01_OCP.brd")
		(comment 1 "Grand Teton / footprints 4284-4286 of 6105")
	)
	(layers
		(0 "F.Cu" signal "TOP")
		(4 "In1.Cu" signal "GND")
		(6 "In2.Cu" signal "IN1")
		(8 "In3.Cu" signal "GND1")
		(10 "In4.Cu" signal "IN2")
		(12 "In5.Cu" signal "GND2")
		(14 "In6.Cu" signal "IN3")
		(16 "In7.Cu" signal "GND3")
		(18 "In8.Cu" signal "VCC")
		(20 "In9.Cu" signal "VCC1")
		(22 "In10.Cu" signal "GND4")
		(24 "In11.Cu" signal "IN4")
		(26 "In12.Cu" signal "GND5")
		(28 "In13.Cu" signal "IN5")
		(30 "In14.Cu" signal "GND6")
		(32 "In15.Cu" signal "IN6")
		(34 "In16.Cu" signal "GND7")
		(2 "B.Cu" signal "BOTTOM")
		(9 "F.Adhes" user "F.Adhesive")
		(11 "B.Adhes" user "B.Adhesive")
		(13 "F.Paste" user "Package Geometry/Pastemask Top")
		(15 "B.Paste" user "Package Geometry/Pastemask Bottom")
		(5 "F.SilkS" user "Ref Des/Silkscreen Top")
		(7 "B.SilkS" user "Ref Des/Silkscreen Bottom")
		(1 "F.Mask" user "Board Geometry/Soldermask Top")
		(3 "B.Mask" user "Board Geometry/Soldermask Bottom")
		(17 "Dwgs.User" user "User.Drawings")
		(19 "Cmts.User" user "User.Comments")
		(21 "Eco1.User" user "User.Eco1")
		(23 "Eco2.User" user "User.Eco2")
		(25 "Edge.Cuts" user "Board Geometry/Outline")
		(27 "Margin" user)
		(31 "F.CrtYd" user "Package Geometry/Place Bound Top")
		(29 "B.CrtYd" user "Package Geometry/Place Bound Bottom")
		(35 "F.Fab" user "Ref Des/Assembly Top")
		(33 "B.Fab" user "Ref Des/Assembly Bottom")
	)
	(footprint ""
		(layer "B.Cu")
		(at 333.868014 -338.137246 -90)
		(property "Reference" "PR140"
			(at 0 0 90)
			(layer "B.SilkS")
			(hide yes)
			(effects
				(font
					(size 1.27 1.27)
				)
				(justify mirror)
			)
		)
		(property "Value" ""
			(at 0 0 90)
			(layer "B.Fab")
			(effects
				(font
					(size 1.27 1.27)
				)
				(justify mirror)
			)
		)
		(duplicate_pad_numbers_are_jumpers no)
		(fp_line
			(start -0.7874 0.4064)
			(end 0.7874 0.4064)
			(stroke
				(width 0.1524)
				(type default)
			)
			(layer "B.SilkS")
		)
		(fp_line
			(start 0.7874 0.4064)
			(end 0.7874 -0.4064)
			(stroke
				(width 0.1524)
				(type default)
			)
			(layer "B.SilkS")
		)
		(fp_line
			(start -0.7874 -0.4064)
			(end -0.7874 0.4064)
			(stroke
				(width 0.1524)
				(type default)
			)
			(layer "B.SilkS")
		)
		(fp_line
			(start 0.7874 -0.4064)
			(end -0.7874 -0.4064)
			(stroke
				(width 0.1524)
				(type default)
			)
			(layer "B.SilkS")
		)
		(fp_line
			(start -0.67945 0.3048)
			(end -0.120396 0.3048)
			(stroke
				(width 0.1)
				(type default)
			)
			(layer "B.Fab")
		)
		(fp_line
			(start -0.120396 0.3048)
			(end -0.120396 0.2794)
			(stroke
				(width 0.1)
				(type default)
			)
			(layer "B.Fab")
		)
		(fp_line
			(start 0.12065 0.3048)
			(end 0.67945 0.3048)
			(stroke
				(width 0.1)
				(type default)
			)
			(layer "B.Fab")
		)
		(fp_line
			(start 0.67945 0.3048)
			(end 0.67945 -0.305054)
			(stroke
				(width 0.1)
				(type default)
			)
			(layer "B.Fab")
		)
		(fp_line
			(start -0.120396 0.2794)
			(end 0.12065 0.2794)
			(stroke
				(width 0.1)
				(type default)
			)
			(layer "B.Fab")
		)
		(fp_line
			(start 0.12065 0.2794)
			(end 0.12065 0.3048)
			(stroke
				(width 0.1)
				(type default)
			)
			(layer "B.Fab")
		)
		(fp_line
			(start -0.12065 -0.2794)
			(end -0.12065 -0.3048)
			(stroke
				(width 0.1)
				(type default)
			)
			(layer "B.Fab")
		)
		(fp_line
			(start 0.12065 -0.2794)
			(end -0.12065 -0.2794)
			(stroke
				(width 0.1)
				(type default)
			)
			(layer "B.Fab")
		)
		(fp_line
			(start -0.67945 -0.3048)
			(end -0.67945 0.3048)
			(stroke
				(width 0.1)
				(type default)
			)
			(layer "B.Fab")
		)
		(fp_line
			(start -0.12065 -0.3048)
			(end -0.67945 -0.3048)
			(stroke
				(width 0.1)
				(type default)
			)
			(layer "B.Fab")
		)
		(fp_line
			(start 0.12065 -0.305054)
			(end 0.12065 -0.2794)
			(stroke
				(width 0.1)
				(type default)
			)
			(layer "B.Fab")
		)
		(fp_line
			(start 0.67945 -0.305054)
			(end 0.12065 -0.305054)
			(stroke
				(width 0.1)
				(type default)
			)
			(layer "B.Fab")
		)
		(pad "1" smd circle
			(at 0.40005 0 90)
			(size 0 0)
			(layers "B.Cu" "B.Mask" "B.Paste")
			(net "PVCCIN_CPU0_PVCC")
		)
		(pad "2" smd circle
			(at -0.40005 0 90)
			(size 0 0)
			(layers "B.Cu" "B.Mask" "B.Paste")
			(net "PVCCIN_CPU0_VDD6")
		)
	)
	(footprint ""
		(layer "B.Cu")
		(at 355.397308 -244.820186 -90)
		(property "Reference" "C393"
			(at 0 0 90)
			(layer "B.SilkS")
			(hide yes)
			(effects
				(font
					(size 1.27 1.27)
				)
				(justify mirror)
			)
		)
		(property "Value" ""
			(at 0 0 90)
			(layer "B.Fab")
			(effects
				(font
					(size 1.27 1.27)
				)
				(justify mirror)
			)
		)
		(duplicate_pad_numbers_are_jumpers no)
		(fp_line
			(start -1.524 0.762)
			(end 1.524 0.762)
			(stroke
				(width 0.1524)
				(type default)
			)
			(layer "B.SilkS")
		)
		(fp_line
			(start 1.524 0.762)
			(end 1.524 -0.762)
			(stroke
				(width 0.1524)
				(type default)
			)
			(layer "B.SilkS")
		)
		(fp_line
			(start -1.524 -0.762)
			(end -1.524 0.762)
			(stroke
				(width 0.1524)
				(type default)
			)
			(layer "B.SilkS")
		)
		(fp_line
			(start 1.524 -0.762)
			(end -1.524 -0.762)
			(stroke
				(width 0.1524)
				(type default)
			)
			(layer "B.SilkS")
		)
		(fp_line
			(start -1.1049 0.724916)
			(end -1.1049 -0.724916)
			(stroke
				(width 0.1)
				(type default)
			)
			(layer "B.Fab")
		)
		(fp_line
			(start 1.1049 0.724916)
			(end -1.1049 0.724916)
			(stroke
				(width 0.1)
				(type default)
			)
			(layer "B.Fab")
		)
		(fp_line
			(start -1.1049 -0.724916)
			(end 1.1049 -0.724916)
			(stroke
				(width 0.1)
				(type default)
			)
			(layer "B.Fab")
		)
		(fp_line
			(start 1.1049 -0.724916)
			(end 1.1049 0.724916)
			(stroke
				(width 0.1)
				(type default)
			)
			(layer "B.Fab")
		)
		(pad "1" smd rect
			(at 0.889 0 270)
			(size 1.016 1.27)
			(layers "B.Cu" "B.Mask" "B.Paste")
			(net "PVCCIN_CPU0")
		)
		(pad "2" smd rect
			(at -0.889 0 270)
			(size 1.016 1.27)
			(layers "B.Cu" "B.Mask" "B.Paste")
			(net "GND")
		)
	)
	(footprint ""
		(layer "B.Cu")
		(at 369.49888 -36.921948)
		(property "Reference" "R2510"
			(at 0 0 0)
			(layer "B.SilkS")
			(hide yes)
			(effects
				(font
					(size 1.27 1.27)
				)
				(justify mirror)
			)
		)
		(property "Value" ""
			(at 0 0 0)
			(layer "B.Fab")
			(effects
				(font
					(size 1.27 1.27)
				)
				(justify mirror)
			)
		)
		(duplicate_pad_numbers_are_jumpers no)
		(fp_line
			(start -0.7874 -0.4064)
			(end -0.7874 0.4064)
			(stroke
				(width 0.1524)
				(type default)
			)
			(layer "B.SilkS")
		)
		(fp_line
			(start -0.7874 0.4064)
			(end 0.7874 0.4064)
			(stroke
				(width 0.1524)
				(type default)
			)
			(layer "B.SilkS")
		)
		(fp_line
			(start 0.7874 -0.4064)
			(end -0.7874 -0.4064)
			(stroke
				(width 0.1524)
				(type default)
			)
			(layer "B.SilkS")
		)
		(fp_line
			(start 0.7874 0.4064)
			(end 0.7874 -0.4064)
			(stroke
				(width 0.1524)
				(type default)
			)
			(layer "B.SilkS")
		)
		(fp_line
			(start -0.67945 -0.3048)
			(end -0.67945 0.3048)
			(stroke
				(width 0.1)
				(type default)
			)
			(layer "B.Fab")
		)
		(fp_line
			(start -0.67945 0.3048)
			(end -0.120396 0.3048)
			(stroke
				(width 0.1)
				(type default)
			)
			(layer "B.Fab")
		)
		(fp_line
			(start -0.12065 -0.3048)
			(end -0.67945 -0.3048)
			(stroke
				(width 0.1)
				(type default)
			)
			(layer "B.Fab")
		)
		(fp_line
			(start -0.12065 -0.2794)
			(end -0.12065 -0.3048)
			(stroke
				(width 0.1)
				(type default)
			)
			(layer "B.Fab")
		)
		(fp_line
			(start -0.120396 0.2794)
			(end 0.12065 0.2794)
			(stroke
				(width 0.1)
				(type default)
			)
			(layer "B.Fab")
		)
		(fp_line
			(start -0.120396 0.3048)
			(end -0.120396 0.2794)
			(stroke
				(width 0.1)
				(type default)
			)
			(layer "B.Fab")
		)
		(fp_line
			(start 0.12065 -0.305054)
			(end 0.12065 -0.2794)
			(stroke
				(width 0.1)
				(type default)
			)
			(layer "B.Fab")
		)
		(fp_line
			(start 0.12065 -0.2794)
			(end -0.12065 -0.2794)
			(stroke
				(width 0.1)
				(type default)
			)
			(layer "B.Fab")
		)
		(fp_line
			(start 0.12065 0.2794)
			(end 0.12065 0.3048)
			(stroke
				(width 0.1)
				(type default)
			)
			(layer "B.Fab")
		)
		(fp_line
			(start 0.12065 0.3048)
			(end 0.67945 0.3048)
			(stroke
				(width 0.1)
				(type default)
			)
			(layer "B.Fab")
		)
		(fp_line
			(start 0.67945 -0.305054)
			(end 0.12065 -0.305054)
			(stroke
				(width 0.1)
				(type default)
			)
			(layer "B.Fab")
		)
		(fp_line
			(start 0.67945 0.3048)
			(end 0.67945 -0.305054)
			(stroke
				(width 0.1)
				(type default)
			)
			(layer "B.Fab")
		)
		(pad "1" smd circle
			(at 0.40005 0 180)
			(size 0 0)
			(layers "B.Cu" "B.Mask" "B.Paste")
			(net "P3V3_AUX")
		)
		(pad "2" smd circle
			(at -0.40005 0 180)
			(size 0 0)
			(layers "B.Cu" "B.Mask" "B.Paste")
			(net "FM_M2_E1S_E6_PEDET")
		)
	)
)
